# S9S_MB_2U (Grand Teton) — schematic netlist excerpt (pin names and nets, part order shuffled) for the footprints in the layout excerpt that follows; sources: Cadence DE-HDL packaged netlist, KiCad conversion of 03242023_DA0F0TMBIJ0_F0T_Motherboard_J_brd_V01_OCP.brd

PR242  Q_RES  0 5% CHIP  pkg 0402LF  page 284 : A = SH_PVCCFA_EHV_FIVRA_CPU1 ; B = SH_PVCCFA_EHV_FIVRA_CPU1_R
PC1670  Q_CAP  22UF 16V 20% X6S  pkg C0805  page 271 : A = SW_P12V_PVCCFA_EHV_FIVRA_CPU0_L ; B = GND

PL11  Q_INDUCTOR4P_14  150NH IND  pkg L_TLM117513Q-151QL_11X7-5XA  page 268
  \1\  = SW_PVCCIN_CPU0_SW4
  \2\  = IND_P0_CPL4
  \3\  = IND_P0_CPL5
  \4\  = PVCCIN_CPU0

(kicad_pcb
	(version 20260206)
	(generator "pcbnew")
	(generator_version "10.0")
	(general
		(thickness 1.6)
		(legacy_teardrops no)
	)
	(paper "A4")
	(title_block
		(title "03242023_DA0F0TMBIJ0_F0T_Motherboard_J_brd_V01_OCP.brd")
		(comment 1 "Grand Teton / footprints 3509-3511 of 6105")
	)
	(layers
		(0 "F.Cu" signal "TOP")
		(4 "In1.Cu" signal "GND")
		(6 "In2.Cu" signal "IN1")
		(8 "In3.Cu" signal "GND1")
		(10 "In4.Cu" signal "IN2")
		(12 "In5.Cu" signal "GND2")
		(14 "In6.Cu" signal "IN3")
		(16 "In7.Cu" signal "GND3")
		(18 "In8.Cu" signal "VCC")
		(20 "In9.Cu" signal "VCC1")
		(22 "In10.Cu" signal "GND4")
		(24 "In11.Cu" signal "IN4")
		(26 "In12.Cu" signal "GND5")
		(28 "In13.Cu" signal "IN5")
		(30 "In14.Cu" signal "GND6")
		(32 "In15.Cu" signal "IN6")
		(34 "In16.Cu" signal "GND7")
		(2 "B.Cu" signal "BOTTOM")
		(9 "F.Adhes" user "F.Adhesive")
		(11 "B.Adhes" user "B.Adhesive")
		(13 "F.Paste" user "Package Geometry/Pastemask Top")
		(15 "B.Paste" user "Package Geometry/Pastemask Bottom")
		(5 "F.SilkS" user "Ref Des/Silkscreen Top")
		(7 "B.SilkS" user "Ref Des/Silkscreen Bottom")
		(1 "F.Mask" user "Board Geometry/Soldermask Top")
		(3 "B.Mask" user "Board Geometry/Soldermask Bottom")
		(17 "Dwgs.User" user "User.Drawings")
		(19 "Cmts.User" user "User.Comments")
		(21 "Eco1.User" user "User.Eco1")
		(23 "Eco2.User" user "User.Eco2")
		(25 "Edge.Cuts" user "Board Geometry/Outline")
		(27 "Margin" user)
		(31 "F.CrtYd" user "Package Geometry/Place Bound Top")
		(29 "B.CrtYd" user "Package Geometry/Place Bound Bottom")
		(35 "F.Fab" user "Ref Des/Assembly Top")
		(33 "B.Fab" user "Ref Des/Assembly Bottom")
	)
	(footprint ""
		(layer "F.Cu")
		(at 114.557556 -355.340666 -90)
		(property "Reference" "PR242"
			(at 0 0 270)
			(layer "F.SilkS")
			(hide yes)
			(effects
				(font
					(size 1.27 1.27)
				)
			)
		)
		(property "Value" ""
			(at 0 0 270)
			(layer "F.Fab")
			(effects
				(font
					(size 1.27 1.27)
				)
			)
		)
		(duplicate_pad_numbers_are_jumpers no)
		(fp_line
			(start -0.7874 0.4064)
			(end -0.7874 -0.4064)
			(stroke
				(width 0.1524)
				(type default)
			)
			(layer "F.SilkS")
		)
		(fp_line
			(start 0.7874 0.4064)
			(end -0.7874 0.4064)
			(stroke
				(width 0.1524)
				(type default)
			)
			(layer "F.SilkS")
		)
		(fp_line
			(start -0.7874 -0.4064)
			(end 0.7874 -0.4064)
			(stroke
				(width 0.1524)
				(type default)
			)
			(layer "F.SilkS")
		)
		(fp_line
			(start 0.7874 -0.4064)
			(end 0.7874 0.4064)
			(stroke
				(width 0.1524)
				(type default)
			)
			(layer "F.SilkS")
		)
		(fp_line
			(start -0.67945 0.3048)
			(end -0.67945 -0.305054)
			(stroke
				(width 0.1)
				(type default)
			)
			(layer "F.Fab")
		)
		(fp_line
			(start -0.12065 0.3048)
			(end -0.67945 0.3048)
			(stroke
				(width 0.1)
				(type default)
			)
			(layer "F.Fab")
		)
		(fp_line
			(start 0.120396 0.3048)
			(end 0.120396 0.2794)
			(stroke
				(width 0.1)
				(type default)
			)
			(layer "F.Fab")
		)
		(fp_line
			(start 0.67945 0.3048)
			(end 0.120396 0.3048)
			(stroke
				(width 0.1)
				(type default)
			)
			(layer "F.Fab")
		)
		(fp_line
			(start -0.12065 0.2794)
			(end -0.12065 0.3048)
			(stroke
				(width 0.1)
				(type default)
			)
			(layer "F.Fab")
		)
		(fp_line
			(start 0.120396 0.2794)
			(end -0.12065 0.2794)
			(stroke
				(width 0.1)
				(type default)
			)
			(layer "F.Fab")
		)
		(fp_line
			(start -0.12065 -0.2794)
			(end 0.12065 -0.2794)
			(stroke
				(width 0.1)
				(type default)
			)
			(layer "F.Fab")
		)
		(fp_line
			(start 0.12065 -0.2794)
			(end 0.12065 -0.3048)
			(stroke
				(width 0.1)
				(type default)
			)
			(layer "F.Fab")
		)
		(fp_line
			(start 0.12065 -0.3048)
			(end 0.67945 -0.3048)
			(stroke
				(width 0.1)
				(type default)
			)
			(layer "F.Fab")
		)
		(fp_line
			(start 0.67945 -0.3048)
			(end 0.67945 0.3048)
			(stroke
				(width 0.1)
				(type default)
			)
			(layer "F.Fab")
		)
		(fp_line
			(start -0.67945 -0.305054)
			(end -0.12065 -0.305054)
			(stroke
				(width 0.1)
				(type default)
			)
			(layer "F.Fab")
		)
		(fp_line
			(start -0.12065 -0.305054)
			(end -0.12065 -0.2794)
			(stroke
				(width 0.1)
				(type default)
			)
			(layer "F.Fab")
		)
		(pad "1" smd circle
			(at -0.40005 0 270)
			(size 0 0)
			(layers "F.Cu" "F.Mask" "F.Paste")
			(net "SH_PVCCFA_EHV_FIVRA_CPU1")
		)
		(pad "2" smd circle
			(at 0.40005 0 270)
			(size 0 0)
			(layers "F.Cu" "F.Mask" "F.Paste")
			(net "SH_PVCCFA_EHV_FIVRA_CPU1_R")
		)
	)
	(footprint ""
		(layer "F.Cu")
		(at 303.543208 -369.067588)
		(property "Reference" "PC1670"
			(at 0 0 0)
			(layer "F.SilkS")
			(hide yes)
			(effects
				(font
					(size 1.27 1.27)
				)
			)
		)
		(property "Value" ""
			(at 0 0 0)
			(layer "F.Fab")
			(effects
				(font
					(size 1.27 1.27)
				)
			)
		)
		(duplicate_pad_numbers_are_jumpers no)
		(fp_line
			(start -1.524 -0.762)
			(end 1.524 -0.762)
			(stroke
				(width 0.1524)
				(type default)
			)
			(layer "F.SilkS")
		)
		(fp_line
			(start -1.524 0.762)
			(end -1.524 -0.762)
			(stroke
				(width 0.1524)
				(type default)
			)
			(layer "F.SilkS")
		)
		(fp_line
			(start 1.524 -0.762)
			(end 1.524 0.762)
			(stroke
				(width 0.1524)
				(type default)
			)
			(layer "F.SilkS")
		)
		(fp_line
			(start 1.524 0.762)
			(end -1.524 0.762)
			(stroke
				(width 0.1524)
				(type default)
			)
			(layer "F.SilkS")
		)
		(fp_line
			(start -1.1049 -0.724916)
			(end -1.1049 0.724916)
			(stroke
				(width 0.1)
				(type default)
			)
			(layer "F.Fab")
		)
		(fp_line
			(start -1.1049 0.724916)
			(end 1.1049 0.724916)
			(stroke
				(width 0.1)
				(type default)
			)
			(layer "F.Fab")
		)
		(fp_line
			(start 1.1049 -0.724916)
			(end -1.1049 -0.724916)
			(stroke
				(width 0.1)
				(type default)
			)
			(layer "F.Fab")
		)
		(fp_line
			(start 1.1049 0.724916)
			(end 1.1049 -0.724916)
			(stroke
				(width 0.1)
				(type default)
			)
			(layer "F.Fab")
		)
		(pad "1" smd rect
			(at -0.889 0 180)
			(size 1.016 1.27)
			(layers "F.Cu" "F.Mask" "F.Paste")
			(net "SW_P12V_PVCCFA_EHV_FIVRA_CPU0_L")
		)
		(pad "2" smd rect
			(at 0.889 0 180)
			(size 1.016 1.27)
			(layers "F.Cu" "F.Mask" "F.Paste")
			(net "GND")
		)
	)
	(footprint ""
		(layer "F.Cu")
		(at 369.461796 -324.445376)
		(property "Reference" "PL11"
			(at 8.906764 3.735578 0)
			(unlocked yes)
			(layer "F.SilkS")
			(effects
				(font
					(size 0.7874 0.5842)
					(thickness 0.1524)
				)
				(justify left)
			)
		)
		(property "Value" ""
			(at 0 0 0)
			(layer "F.Fab")
			(effects
				(font
					(size 1.27 1.27)
				)
			)
		)
		(duplicate_pad_numbers_are_jumpers no)
		(fp_line
			(start -3.750056 -5.500116)
			(end -2.393442 -5.500116)
			(stroke
				(width 0.1524)
				(type default)
			)
			(layer "F.SilkS")
		)
		(fp_line
			(start -3.750056 5.500116)
			(end -3.750056 -5.500116)
			(stroke
				(width 0.1524)
				(type default)
			)
			(layer "F.SilkS")
		)
		(fp_line
			(start -2.393442 5.500116)
			(end -3.750056 5.500116)
			(stroke
				(width 0.1524)
				(type default)
			)
			(layer "F.SilkS")
		)
		(fp_line
			(start 2.393442 5.500116)
			(end 3.750056 5.500116)
			(stroke
				(width 0.1524)
				(type default)
			)
			(layer "F.SilkS")
		)
		(fp_line
			(start 3.750056 -5.500116)
			(end 2.393442 -5.500116)
			(stroke
				(width 0.1524)
				(type default)
			)
			(layer "F.SilkS")
		)
		(fp_line
			(start 3.750056 5.500116)
			(end 3.750056 -5.500116)
			(stroke
				(width 0.1524)
				(type default)
			)
			(layer "F.SilkS")
		)
		(fp_poly
			(pts
				(xy -3.302762 -6.909816) (xy -2.943352 -5.832094) (xy -4.021074 -6.191504)
			)
			(stroke
				(width 0)
				(type default)
			)
			(fill yes)
			(layer "F.SilkS")
		)
		(fp_line
			(start -3.750056 -5.500116)
			(end -3.750056 5.500116)
			(stroke
				(width 0.1)
				(type default)
			)
			(layer "F.Fab")
		)
		(fp_line
			(start -3.750056 5.500116)
			(end 3.750056 5.500116)
			(stroke
				(width 0.1)
				(type default)
			)
			(layer "F.Fab")
		)
		(fp_line
			(start 3.750056 -5.500116)
			(end -3.750056 -5.500116)
			(stroke
				(width 0.1)
				(type default)
			)
			(layer "F.Fab")
		)
		(fp_line
			(start 3.750056 5.500116)
			(end 3.750056 -5.500116)
			(stroke
				(width 0.1)
				(type default)
			)
			(layer "F.Fab")
		)
		(fp_poly
			(pts
				(xy -4.9276 -4.757928) (xy -4.9276 -3.741928) (xy -3.9116 -4.249928)
			)
			(stroke
				(width 0)
				(type default)
			)
			(fill yes)
			(layer "F.Fab")
		)
		(pad "1" smd rect
			(at 0 -4.249928 270)
			(size 2.413 4.5212)
			(layers "F.Cu" "F.Mask" "F.Paste")
			(net "SW_PVCCIN_CPU0_SW4")
		)
		(pad "2" smd rect
			(at 0 -1.175004 270)
			(size 1.3716 4.5212)
			(layers "F.Cu" "F.Mask" "F.Paste")
			(net "IND_P0_CPL4")
		)
		(pad "3" smd rect
			(at 0 1.175004 270)
			(size 1.3716 4.5212)
			(layers "F.Cu" "F.Mask" "F.Paste")
			(net "IND_P0_CPL5")
		)
		(pad "4" smd rect
			(at 0 4.249928 270)
			(size 2.413 4.5212)
			(layers "F.Cu" "F.Mask" "F.Paste")
			(net "PVCCIN_CPU0")
		)
	)
)
